# TIMECARD (Time Appliance Project (Time Card)) — schematic netlist excerpt (pin names and nets, part order shuffled) for the footprints in the layout excerpt that follows; sources: Cadence DE-HDL packaged netlist, KiCad conversion of R4006-B0001-02_R01.brd

C26  CAPACITOR  0.1UF 10%  pkg SMC_0402R_H022  page 9 : \1\ = C_CPU_RX_PCIE_MGT1_TXP ; \2\ = CPU_RX_PCIE_MGT1_TXP
R503  RESISTOR  4.7KOHM 1%  pkg SMC_0402R_H016  page 11 : \1\ = ANT2_IN ; \2\ = SG

(kicad_pcb
	(version 20260206)
	(generator "pcbnew")
	(generator_version "10.0")
	(general
		(thickness 1.6)
		(legacy_teardrops no)
	)
	(paper "A4")
	(title_block
		(title "timecard-production-celestica-r4006 — R4006-B0001-02_R01.brd")
		(comment 1 "Time Appliance Project (Time Card) / footprints 1041-1042 of 1113")
	)
	(layers
		(0 "F.Cu" signal "TOP")
		(4 "In1.Cu" signal "L02_GND1")
		(6 "In2.Cu" signal "L03_SIG1")
		(8 "In3.Cu" signal "L04_GND2")
		(10 "In4.Cu" signal "L05_VCC1")
		(12 "In5.Cu" signal "L06_VCC2")
		(14 "In6.Cu" signal "L07_GND3")
		(16 "In7.Cu" signal "L08_SIG2")
		(18 "In8.Cu" signal "L09_GND4")
		(2 "B.Cu" signal "BOTTOM")
		(9 "F.Adhes" user "F.Adhesive")
		(11 "B.Adhes" user "B.Adhesive")
		(13 "F.Paste" user "Package Geometry/Pastemask Top")
		(15 "B.Paste" user "Package Geometry/Pastemask Bottom")
		(5 "F.SilkS" user "Ref Des/Silkscreen Top")
		(7 "B.SilkS" user "Ref Des/Silkscreen Bottom")
		(1 "F.Mask" user "Board Geometry/Soldermask Top")
		(3 "B.Mask" user "Board Geometry/Soldermask Bottom")
		(17 "Dwgs.User" user "User.Drawings")
		(19 "Cmts.User" user "User.Comments")
		(21 "Eco1.User" user "User.Eco1")
		(23 "Eco2.User" user "User.Eco2")
		(25 "Edge.Cuts" user "Board Geometry/Outline")
		(27 "Margin" user)
		(31 "F.CrtYd" user "Package Geometry/Place Bound Top")
		(29 "B.CrtYd" user "Package Geometry/Place Bound Bottom")
		(35 "F.Fab" user "Ref Des/Assembly Top")
		(33 "B.Fab" user "Ref Des/Assembly Bottom")
	)
	(footprint ""
		(layer "B.Cu")
		(at 67.514978 -15.367 -90)
		(property "Reference" "C26"
			(at 3.048 0.236728 270)
			(unlocked yes)
			(layer "B.SilkS")
			(effects
				(font
					(size 0.635 0.4064)
					(thickness 0.1524)
				)
				(justify mirror)
			)
		)
		(property "Value" "VAL*"
			(at -0.0762 2.067306 270)
			(unlocked yes)
			(layer "B.Fab")
			(hide yes)
			(effects
				(font
					(size 0.7874 0.5842)
					(thickness 0.1524)
				)
				(justify mirror)
			)
		)
		(property "Tolerance" "TOL*"
			(at -0.0762 3.032506 270)
			(unlocked yes)
			(layer "Cmts.User")
			(hide yes)
			(effects
				(font
					(size 0.7874 0.5842)
					(thickness 0.1524)
				)
				(justify mirror)
			)
		)
		(property "User Part Number" "PARTNUM*"
			(at -0.1016 4.023106 270)
			(unlocked yes)
			(layer "Cmts.User")
			(hide yes)
			(effects
				(font
					(size 0.7874 0.5842)
					(thickness 0.1524)
				)
				(justify mirror)
			)
		)
		(property "Device Type" "CAPACITOR-G105-0B104-CK,0.1UF,A"
			(at -0.0508 1.127506 270)
			(unlocked yes)
			(layer "B.Fab")
			(hide yes)
			(effects
				(font
					(size 0.7874 0.5842)
					(thickness 0.1524)
				)
				(justify mirror)
			)
		)
		(duplicate_pad_numbers_are_jumpers no)
		(fp_line
			(start -1.143 0.5588)
			(end -1.143 -0.5588)
			(stroke
				(width 0.1)
				(type default)
			)
			(layer "B.SilkS")
		)
		(fp_line
			(start 1.143 0.5588)
			(end -1.143 0.5588)
			(stroke
				(width 0.1)
				(type default)
			)
			(layer "B.SilkS")
		)
		(fp_line
			(start -1.143 -0.5588)
			(end 1.143 -0.5588)
			(stroke
				(width 0.1)
				(type default)
			)
			(layer "B.SilkS")
		)
		(fp_line
			(start 1.143 -0.5588)
			(end 1.143 0.5588)
			(stroke
				(width 0.1)
				(type default)
			)
			(layer "B.SilkS")
		)
		(fp_rect
			(start 1.143 0.5588)
			(end -1.143 -0.5588)
			(stroke
				(width 0)
				(type default)
			)
			(fill no)
			(layer "B.CrtYd")
		)
		(fp_line
			(start -0.508 0.3048)
			(end -0.508 -0.3048)
			(stroke
				(width 0.1)
				(type default)
			)
			(layer "B.Fab")
		)
		(fp_line
			(start 0.508 0.3048)
			(end -0.508 0.3048)
			(stroke
				(width 0.1)
				(type default)
			)
			(layer "B.Fab")
		)
		(fp_line
			(start -0.508 -0.3048)
			(end 0.508 -0.3048)
			(stroke
				(width 0.1)
				(type default)
			)
			(layer "B.Fab")
		)
		(fp_line
			(start 0.508 -0.3048)
			(end 0.508 0.3048)
			(stroke
				(width 0.1)
				(type default)
			)
			(layer "B.Fab")
		)
		(pad "1" smd rect
			(at 0.5334 0 90)
			(size 0.7112 0.6096)
			(layers "B.Cu" "B.Mask" "B.Paste")
			(net "C_CPU_RX_PCIE_MGT1_TXP")
		)
		(pad "2" smd rect
			(at -0.5334 0 90)
			(size 0.7112 0.6096)
			(layers "B.Cu" "B.Mask" "B.Paste")
			(net "CPU_RX_PCIE_MGT1_TXP")
		)
		(zone
			(layer "B.Cu")
			(hatch none 0.5)
			(connect_pads
				(clearance 0)
			)
			(min_thickness 0.25)
			(keepout
				(tracks allowed)
				(vias not_allowed)
				(pads allowed)
				(copperpour not_allowed)
				(footprints allowed)
			)
			(placement
				(enabled no)
				(sheetname "")
			)
			(fill
				(thermal_gap 0.5)
				(thermal_bridge_width 0.5)
				(island_removal_mode 0)
			)
			(polygon
				(pts
					(xy 67.210178 -15.2908) (xy 67.819778 -15.2908) (xy 67.819778 -15.4432) (xy 67.210178 -15.4432)
				)
			)
		)
	)
	(footprint ""
		(layer "B.Cu")
		(at 119.347234 -52.82311 180)
		(property "Reference" "R503"
			(at 2.253234 -0.02286 0)
			(unlocked yes)
			(layer "B.SilkS")
			(effects
				(font
					(size 0.635 0.4064)
					(thickness 0.1524)
				)
				(justify mirror)
			)
		)
		(property "Value" "VAL*"
			(at 0 3.718306 180)
			(unlocked yes)
			(layer "B.Fab")
			(hide yes)
			(effects
				(font
					(size 0.7874 0.5842)
					(thickness 0.127)
				)
				(justify mirror)
			)
		)
		(property "Tolerance" "TOL*"
			(at 0 4.861306 180)
			(unlocked yes)
			(layer "Cmts.User")
			(hide yes)
			(effects
				(font
					(size 0.7874 0.5842)
					(thickness 0.127)
				)
				(justify mirror)
			)
		)
		(property "User Part Number" "PARTNUM*"
			(at 0 2.575306 180)
			(unlocked yes)
			(layer "Cmts.User")
			(hide yes)
			(effects
				(font
					(size 0.7874 0.5842)
					(thickness 0.127)
				)
				(justify mirror)
			)
		)
		(property "Device Type" "RESISTOR-G155-14701-01,4.7KOHMA"
			(at 0 1.432306 180)
			(unlocked yes)
			(layer "B.Fab")
			(hide yes)
			(effects
				(font
					(size 0.7874 0.5842)
					(thickness 0.127)
				)
				(justify mirror)
			)
		)
		(duplicate_pad_numbers_are_jumpers no)
		(fp_line
			(start 0.970026 0.4699)
			(end 0.970026 -0.4699)
			(stroke
				(width 0.1)
				(type default)
			)
			(layer "B.SilkS")
		)
		(fp_line
			(start 0.970026 -0.4699)
			(end -0.970026 -0.4699)
			(stroke
				(width 0.1)
				(type default)
			)
			(layer "B.SilkS")
		)
		(fp_line
			(start -0.970026 0.4699)
			(end 0.970026 0.4699)
			(stroke
				(width 0.1)
				(type default)
			)
			(layer "B.SilkS")
		)
		(fp_line
			(start -0.970026 -0.4699)
			(end -0.970026 0.4699)
			(stroke
				(width 0.1)
				(type default)
			)
			(layer "B.SilkS")
		)
		(fp_poly
			(pts
				(xy 0.970026 0.4699) (xy -0.970026 0.4699) (xy -0.970026 -0.4699) (xy 0.970026 -0.4699)
			)
			(stroke
				(width 0)
				(type default)
			)
			(fill no)
			(layer "B.CrtYd")
		)
		(fp_line
			(start 0.508 0.3048)
			(end 0.508 -0.3048)
			(stroke
				(width 0.1)
				(type default)
			)
			(layer "B.Fab")
		)
		(fp_line
			(start 0.508 -0.3048)
			(end -0.508 -0.3048)
			(stroke
				(width 0.1)
				(type default)
			)
			(layer "B.Fab")
		)
		(fp_line
			(start -0.508 0.3048)
			(end 0.508 0.3048)
			(stroke
				(width 0.1)
				(type default)
			)
			(layer "B.Fab")
		)
		(fp_line
			(start -0.508 -0.3048)
			(end -0.508 0.3048)
			(stroke
				(width 0.1)
				(type default)
			)
			(layer "B.Fab")
		)
		(pad "1" smd circle
			(at 0.500126 0)
			(size 0.635 0.635)
			(layers "B.Cu" "B.Mask" "B.Paste")
			(net "ANT2_IN")
		)
		(pad "2" smd circle
			(at -0.500126 0)
			(size 0.635 0.635)
			(layers "B.Cu" "B.Mask" "B.Paste")
			(net "SG")
		)
	)
)
